(kicad_pcb
	(version 20241229)
	(generator "pcbnew")
	(generator_version "9.0")
	(general
		(thickness 1.711)
		(legacy_teardrops no)
	)
	(paper "A4")
	(title_block
		(title "Antmicro Baseboard for Jetson AGX Thor")
		(date "2026-02-18")
		(rev "1.1.0")
		(company "Antmicro Ltd")
		(comment 1 "www.antmicro.com")
		(comment 9 "footprints 121-122 of 1170")
	)
	(layers
		(0 "F.Cu" signal)
		(4 "In1.Cu" signal)
		(6 "In2.Cu" signal)
		(8 "In3.Cu" signal)
		(10 "In4.Cu" jumper)
		(12 "In5.Cu" signal)
		(14 "In6.Cu" signal)
		(16 "In7.Cu" signal)
		(18 "In8.Cu" signal)
		(2 "B.Cu" signal)
		(9 "F.Adhes" user "F.Adhesive")
		(11 "B.Adhes" user "B.Adhesive")
		(13 "F.Paste" user)
		(15 "B.Paste" user)
		(5 "F.SilkS" user "F.Silkscreen")
		(7 "B.SilkS" user "B.Silkscreen")
		(1 "F.Mask" user)
		(3 "B.Mask" user)
		(17 "Dwgs.User" user "User.Drawings")
		(19 "Cmts.User" user "User.Comments")
		(21 "Eco1.User" user "User.Eco1")
		(23 "Eco2.User" user "User.Eco2")
		(25 "Edge.Cuts" user)
		(27 "Margin" user)
		(31 "F.CrtYd" user "F.Courtyard")
		(29 "B.CrtYd" user "B.Courtyard")
		(35 "F.Fab" user)
		(33 "B.Fab" user)
	)
	(footprint "antmicro-footprints:DHVQFN-14-1EP_2.5x3mm"
		(layer "F.Cu")
		(at 152.48 118.75 180)
		(property "Reference" "U1"
			(at 1.18 2.95 0)
			(layer "F.SilkS")
			(effects
				(font
					(size 0.7 0.7)
					(thickness 0.15)
				)
				(justify right top)
			)
		)
		(property "Value" "NTS0104_DHVQFN"
			(at 0 2.897999 0)
			(layer "F.Fab")
			(effects
				(font
					(size 0.7 0.7)
					(thickness 0.15)
				)
				(justify right top)
			)
		)
		(property "Datasheet" "https://www.nxp.com/docs/en/data-sheet/NTS0104.pdf"
			(at 0 0 0)
			(layer "F.Fab")
			(hide yes)
			(effects
				(font
					(size 1.27 1.27)
					(thickness 0.15)
				)
			)
		)
		(property "Description" "Voltage Level Translator Bidirectional 1 Circuit 4 Channel 50Mbps 14-DHVQFN (2.5x3)"
			(at 0 0 0)
			(layer "F.Fab")
			(hide yes)
			(effects
				(font
					(size 1.27 1.27)
					(thickness 0.15)
				)
			)
		)
		(property "MPN" "NTS0104BQ"
			(at 0 0 180)
			(unlocked yes)
			(layer "F.Fab")
			(hide yes)
			(effects
				(font
					(size 1 1)
					(thickness 0.15)
				)
			)
		)
		(property "Manufacturer" "NXP"
			(at 0 0 180)
			(unlocked yes)
			(layer "F.Fab")
			(hide yes)
			(effects
				(font
					(size 1 1)
					(thickness 0.15)
				)
			)
		)
		(property "Author" "Antmicro"
			(at 0 0 180)
			(unlocked yes)
			(layer "F.Fab")
			(hide yes)
			(effects
				(font
					(size 1 1)
					(thickness 0.15)
				)
			)
		)
		(property "License" "Apache-2.0"
			(at 0 0 180)
			(unlocked yes)
			(layer "F.Fab")
			(hide yes)
			(effects
				(font
					(size 1 1)
					(thickness 0.15)
				)
			)
		)
		(sheetname "/SoM_IO/")
		(sheetfile "som_io.kicad_sch")
		(attr smd)
		(fp_line
			(start 1.35 1.6)
			(end 1.35 1.249)
			(stroke
				(width 0.15)
				(type solid)
			)
			(layer "F.SilkS")
		)
		(fp_line
			(start 1.35 -1.601)
			(end 1.35 -1.25)
			(stroke
				(width 0.15)
				(type solid)
			)
			(layer "F.SilkS")
		)
		(fp_line
			(start 1.35 -1.601)
			(end 0.494 -1.601)
			(stroke
				(width 0.15)
				(type solid)
			)
			(layer "F.SilkS")
		)
		(fp_line
			(start 0.494 1.6)
			(end 1.35 1.6)
			(stroke
				(width 0.15)
				(type solid)
			)
			(layer "F.SilkS")
		)
		(fp_line
			(start -1.35 -1.601)
			(end -1.35 -1.25)
			(stroke
				(width 0.15)
				(type solid)
			)
			(layer "F.SilkS")
		)
		(fp_line
			(start -1.351 1.6)
			(end -0.5 1.6)
			(stroke
				(width 0.15)
				(type solid)
			)
			(layer "F.SilkS")
		)
		(fp_line
			(start -1.351 1.6)
			(end -1.351 1.249)
			(stroke
				(width 0.15)
				(type solid)
			)
			(layer "F.SilkS")
		)
		(fp_line
			(start -1.351 -1.601)
			(end -0.499999 -1.601)
			(stroke
				(width 0.15)
				(type solid)
			)
			(layer "F.SilkS")
		)
		(fp_circle
			(center -0.7 -1.85)
			(end -0.653 -1.85)
			(stroke
				(width 0.15)
				(type solid)
			)
			(fill yes)
			(layer "F.SilkS")
		)
		(fp_poly
			(pts
				(xy -1.85 -2) (xy 1.8 -2) (xy 1.8 1.95) (xy -1.85 1.95)
			)
			(stroke
				(width 0.05)
				(type solid)
			)
			(fill no)
			(layer "F.CrtYd")
		)
		(fp_line
			(start 1.249 -1.5)
			(end 1.248999 1.499)
			(stroke
				(width 0.15)
				(type solid)
			)
			(layer "F.Fab")
		)
		(fp_line
			(start 1.248999 1.499)
			(end -1.25 1.499001)
			(stroke
				(width 0.15)
				(type solid)
			)
			(layer "F.Fab")
		)
		(fp_line
			(start -1 -1.5)
			(end 1.249 -1.5)
			(stroke
				(width 0.15)
				(type solid)
			)
			(layer "F.Fab")
		)
		(fp_line
			(start -1.25 1.499001)
			(end -1.25 -1.25)
			(stroke
				(width 0.15)
				(type solid)
			)
			(layer "F.Fab")
		)
		(fp_line
			(start -1.25 -1.25)
			(end -1 -1.5)
			(stroke
				(width 0.15)
				(type solid)
			)
			(layer "F.Fab")
		)
		(fp_text user "${REFERENCE}"
			(at -1.841 4.896999 0)
			(layer "F.Fab")
			(effects
				(font
					(size 0.7 0.7)
					(thickness 0.15)
				)
				(justify right top)
			)
		)
		(fp_text user "License: Apache-2.0"
			(at -1.841001 6.097 0)
			(layer "F.Fab")
			(effects
				(font
					(size 0.7 0.7)
					(thickness 0.15)
				)
				(justify right top)
			)
		)
		(fp_text user "Author: Antmicro"
			(at -1.841001 7.296 0)
			(layer "F.Fab")
			(effects
				(font
					(size 0.7 0.7)
					(thickness 0.15)
				)
				(justify right top)
			)
		)
		(pad "1" smd oval
			(at -0.25 -1.5 180)
			(size 0.3 0.8)
			(layers "F.Cu" "F.Mask" "F.Paste")
			(net 11 "+1V8")
			(pinfunction "VCC_A")
			(pintype "power_in")
		)
		(pad "2" smd oval
			(at -1.25 -1 270)
			(size 0.3 0.8)
			(layers "F.Cu" "F.Mask" "F.Paste")
			(net 331 "/SoM_IO/I2C0_SDA_1V8")
			(pinfunction "A1")
			(pintype "passive")
		)
		(pad "3" smd oval
			(at -1.25 -0.5 270)
			(size 0.3 0.8)
			(layers "F.Cu" "F.Mask" "F.Paste")
			(net 317 "/SoM_IO/I2C0_SCL_1V8")
			(pinfunction "A2")
			(pintype "passive")
		)
		(pad "4" smd oval
			(at -1.249999 0 270)
			(size 0.3 0.8)
			(layers "F.Cu" "F.Mask" "F.Paste")
			(net 145 "/SoM_IO/I2C3_SDA_1V8")
			(pinfunction "A3")
			(pintype "passive")
		)
		(pad "5" smd oval
			(at -1.25 0.494 270)
			(size 0.3 0.8)
			(layers "F.Cu" "F.Mask" "F.Paste")
			(net 60 "/SoM_IO/I2C3_SCL_1V8")
			(pinfunction "A4")
			(pintype "passive")
		)
		(pad "6" smd oval
			(at -1.25 0.994001 270)
			(size 0.3 0.8)
			(layers "F.Cu" "F.Mask" "F.Paste")
			(net 1321 "unconnected-(U1-NC-Pad6)")
			(pinfunction "NC")
			(pintype "no_connect")
		)
		(pad "7" smd oval
			(at -0.25 1.499 180)
			(size 0.3 0.8)
			(layers "F.Cu" "F.Mask" "F.Paste")
			(net 1 "GND")
			(pinfunction "GND")
			(pintype "power_in")
		)
		(pad "8" smd oval
			(at 0.244 1.499 180)
			(size 0.3 0.8)
			(layers "F.Cu" "F.Mask" "F.Paste")
			(net 11 "+1V8")
			(pinfunction "OE")
			(pintype "passive")
		)
		(pad "9" smd oval
			(at 1.249 0.994001 270)
			(size 0.3 0.8)
			(layers "F.Cu" "F.Mask" "F.Paste")
			(net 1320 "unconnected-(U1-NC-Pad9)")
			(pinfunction "NC")
			(pintype "no_connect")
		)
		(pad "10" smd oval
			(at 1.249 0.494 270)
			(size 0.3 0.8)
			(layers "F.Cu" "F.Mask" "F.Paste")
			(net 1000 "/SFP/I2C_{SFP}.SCL")
			(pinfunction "B4")
			(pintype "passive")
		)
		(pad "11" smd oval
			(at 1.248999 0 270)
			(size 0.3 0.8)
			(layers "F.Cu" "F.Mask" "F.Paste")
			(net 999 "/SFP/I2C_{SFP}.SDA")
			(pinfunction "B3")
			(pintype "passive")
		)
		(pad "12" smd oval
			(at 1.249 -0.5 270)
			(size 0.3 0.8)
			(layers "F.Cu" "F.Mask" "F.Paste")
			(net 561 "/Expansion connector/I2C0.SDA")
			(pinfunction "B2")
			(pintype "passive")
		)
		(pad "13" smd oval
			(at 1.249 -1 270)
			(size 0.3 0.8)
			(layers "F.Cu" "F.Mask" "F.Paste")
			(net 407 "/Expansion connector/I2C0.SCL")
			(pinfunction "B1")
			(pintype "passive")
		)
		(pad "14" smd oval
			(at 0.244 -1.5 180)
			(size 0.3 0.8)
			(layers "F.Cu" "F.Mask" "F.Paste")
			(net 2 "+3V3")
			(pinfunction "VCC_B")
			(pintype "power_in")
		)
		(pad "15" smd rect
			(at 0 0 180)
			(size 1 1.5)
			(layers "F.Cu" "F.Mask" "F.Paste")
			(net 1 "GND")
			(pinfunction "GNDPAD")
			(pintype "power_in")
		)
	)
	(footprint "antmicro-footprints:LED_0603_1608Metric_G"
		(layer "F.Cu")
		(at 173 55.31 -90)
		(descr "LED SMD 0603 Green")
		(tags "LED SMD 0603 Green")
		(property "Reference" "D42"
			(at -0.88 1.5 90)
			(layer "F.SilkS")
			(effects
				(font
					(size 0.7 0.7)
					(thickness 0.15)
				)
				(justify right top)
			)
		)
		(property "Value" "LED_G_0603_LTST-C190GKT"
			(at -0.001 1.599 90)
			(layer "F.Fab")
			(effects
				(font
					(size 0.7 0.7)
					(thickness 0.15)
				)
				(justify right top)
			)
		)
		(property "Datasheet" "https://media.digikey.com/pdf/Data%20Sheets/Lite-On%20PDFs/LTST-C190GKT.pdf"
			(at 0 0 90)
			(layer "F.Fab")
			(hide yes)
			(effects
				(font
					(size 1.27 1.27)
					(thickness 0.15)
				)
			)
		)
		(property "Description" "LED, Green, SMD, 0603, 20 mA, 2.1 V, 569 nm"
			(at 0 0 90)
			(layer "F.Fab")
			(hide yes)
			(effects
				(font
					(size 1.27 1.27)
					(thickness 0.15)
				)
			)
		)
		(property "MPN" "LTST-C190GKT"
			(at 0 0 270)
			(unlocked yes)
			(layer "F.Fab")
			(hide yes)
			(effects
				(font
					(size 1 1)
					(thickness 0.15)
				)
			)
		)
		(property "Manufacturer" "Lite-On"
			(at 0 0 270)
			(unlocked yes)
			(layer "F.Fab")
			(hide yes)
			(effects
				(font
					(size 1 1)
					(thickness 0.15)
				)
			)
		)
		(property "Author" "Antmicro"
			(at 0 0 270)
			(unlocked yes)
			(layer "F.Fab")
			(hide yes)
			(effects
				(font
					(size 1 1)
					(thickness 0.15)
				)
			)
		)
		(property "License" "Apache-2.0"
			(at 0 0 270)
			(unlocked yes)
			(layer "F.Fab")
			(hide yes)
			(effects
				(font
					(size 1 1)
					(thickness 0.15)
				)
			)
		)
		(property "Color" "Green"
			(at 0 0 270)
			(unlocked yes)
			(layer "F.Fab")
			(hide yes)
			(effects
				(font
					(size 1 1)
					(thickness 0.15)
				)
			)
		)
		(sheetname "/Power/")
		(sheetfile "power.kicad_sch")
		(attr smd)
		(fp_line
			(start 0.22 0.35)
			(end -0.22 0.35)
			(stroke
				(width 0.15)
				(type solid)
			)
			(layer "F.SilkS")
		)
		(fp_line
			(start -0.094672 0.201008)
			(end -0.094672 -0.198992)
			(stroke
				(width 0.1)
				(type solid)
			)
			(layer "F.SilkS")
		)
		(fp_line
			(start 0.105328 0.201008)
			(end -0.094672 0.001008)
			(stroke
				(width 0.1)
				(type solid)
			)
			(layer "F.SilkS")
		)
		(fp_line
			(start 0.105328 0.201008)
			(end 0.105328 -0.198992)
			(stroke
				(width 0.1)
				(type solid)
			)
			(layer "F.SilkS")
		)
		(fp_line
			(start -0.094672 0.001008)
			(end -0.24 0.001008)
			(stroke
				(width 0.1)
				(type solid)
			)
			(layer "F.SilkS")
		)
		(fp_line
			(start -0.094672 0.001008)
			(end 0.105328 -0.198992)
			(stroke
				(width 0.1)
				(type solid)
			)
			(layer "F.SilkS")
		)
		(fp_line
			(start 0.105328 0.001008)
			(end 0.24 0.001)
			(stroke
				(width 0.1)
				(type solid)
			)
			(layer "F.SilkS")
		)
		(fp_line
			(start -1.18 -0.319)
			(end -1.18 0.321)
			(stroke
				(width 0.15)
				(type solid)
			)
			(layer "F.SilkS")
		)
		(fp_line
			(start 0.22 -0.35)
			(end -0.22 -0.35)
			(stroke
				(width 0.15)
				(type solid)
			)
			(layer "F.SilkS")
		)
		(fp_rect
			(start 1.25 0.65)
			(end -1.25 -0.65)
			(stroke
				(width 0.05)
				(type solid)
			)
			(fill no)
			(layer "F.CrtYd")
		)
		(fp_line
			(start -0.199 0.2)
			(end -0.199 0.1)
			(stroke
				(width 0.15)
				(type solid)
			)
			(layer "F.Fab")
		)
		(fp_line
			(start 0.201 0.2)
			(end 0.201 0)
			(stroke
				(width 0.15)
				(type solid)
			)
			(layer "F.Fab")
		)
		(fp_line
			(start -0.199 0)
			(end -0.597 0)
			(stroke
				(width 0.15)
				(type solid)
			)
			(layer "F.Fab")
		)
		(fp_line
			(start -0.101 0)
			(end 0.201 0.2)
			(stroke
				(width 0.15)
				(type solid)
			)
			(layer "F.Fab")
		)
		(fp_line
			(start 0.201 0)
			(end 0.201 -0.202)
			(stroke
				(width 0.15)
				(type solid)
			)
			(layer "F.Fab")
		)
		(fp_line
			(start 0.599 0)
			(end 0.201 0)
			(stroke
				(width 0.15)
				(type solid)
			)
			(layer "F.Fab")
		)
		(fp_line
			(start -0.199 -0.202)
			(end -0.199 0.1)
			(stroke
				(width 0.15)
				(type solid)
			)
			(layer "F.Fab")
		)
		(fp_line
			(start 0.201 -0.202)
			(end -0.101 0)
			(stroke
				(width 0.15)
				(type solid)
			)
			(layer "F.Fab")
		)
		(fp_rect
			(start 0.848 0.4)
			(end -0.85 -0.402)
			(stroke
				(width 0.15)
				(type solid)
			)
			(fill no)
			(layer "F.Fab")
		)
		(fp_text user "Author: Antmicro"
			(at -1.4224 4.799 90)
			(layer "F.Fab")
			(effects
				(font
					(size 0.7 0.7)
					(thickness 0.15)
				)
				(justify right top)
			)
		)
		(fp_text user "${REFERENCE}"
			(at -1.4224 5.999 90)
			(layer "F.Fab")
			(effects
				(font
					(size 0.7 0.7)
					(thickness 0.15)
				)
				(justify right top)
			)
		)
		(fp_text user "License: Apache-2.0"
			(at -1.4224 3.599 90)
			(layer "F.Fab")
			(effects
				(font
					(size 0.7 0.7)
					(thickness 0.15)
				)
				(justify right top)
			)
		)
		(pad "1" smd roundrect
			(at -0.7 0 90)
			(size 0.8 1)
			(layers "F.Cu" "F.Mask" "F.Paste")
			(roundrect_rratio 0.2)
			(net 1 "GND")
			(pinfunction "C")
			(pintype "passive")
		)
		(pad "2" smd roundrect
			(at 0.7 0 90)
			(size 0.8 1)
			(layers "F.Cu" "F.Mask" "F.Paste")
			(roundrect_rratio 0.2)
			(net 1127 "Net-(D42-A)")
			(pinfunction "A")
			(pintype "passive")
		)
	)
)
